(kicad_pcb
	(version 20260206)
	(generator "pcbnew")
	(generator_version "10.0")
	(general
		(thickness 1.6)
		(legacy_teardrops no)
	)
	(paper "A4")
	(title_block
		(title "03242023_DA0F0TMBIJ0_F0T_Motherboard_J_brd_V01_OCP.brd")
		(comment 1 "Grand Teton / footprints 4039-4045 of 6105")
	)
	(layers
		(0 "F.Cu" signal "TOP")
		(4 "In1.Cu" signal "GND")
		(6 "In2.Cu" signal "IN1")
		(8 "In3.Cu" signal "GND1")
		(10 "In4.Cu" signal "IN2")
		(12 "In5.Cu" signal "GND2")
		(14 "In6.Cu" signal "IN3")
		(16 "In7.Cu" signal "GND3")
		(18 "In8.Cu" signal "VCC")
		(20 "In9.Cu" signal "VCC1")
		(22 "In10.Cu" signal "GND4")
		(24 "In11.Cu" signal "IN4")
		(26 "In12.Cu" signal "GND5")
		(28 "In13.Cu" signal "IN5")
		(30 "In14.Cu" signal "GND6")
		(32 "In15.Cu" signal "IN6")
		(34 "In16.Cu" signal "GND7")
		(2 "B.Cu" signal "BOTTOM")
		(9 "F.Adhes" user "F.Adhesive")
		(11 "B.Adhes" user "B.Adhesive")
		(13 "F.Paste" user "Package Geometry/Pastemask Top")
		(15 "B.Paste" user "Package Geometry/Pastemask Bottom")
		(5 "F.SilkS" user "Ref Des/Silkscreen Top")
		(7 "B.SilkS" user "Ref Des/Silkscreen Bottom")
		(1 "F.Mask" user "Board Geometry/Soldermask Top")
		(3 "B.Mask" user "Board Geometry/Soldermask Bottom")
		(17 "Dwgs.User" user "User.Drawings")
		(19 "Cmts.User" user "User.Comments")
		(21 "Eco1.User" user "User.Eco1")
		(23 "Eco2.User" user "User.Eco2")
		(25 "Edge.Cuts" user "Board Geometry/Outline")
		(27 "Margin" user)
		(31 "F.CrtYd" user "Package Geometry/Place Bound Top")
		(29 "B.CrtYd" user "Package Geometry/Place Bound Bottom")
		(35 "F.Fab" user "Ref Des/Assembly Top")
		(33 "B.Fab" user "Ref Des/Assembly Bottom")
	)
	(footprint ""
		(layer "F.Cu")
		(at 300.260258 -367.378996 -90)
		(property "Reference" "PC607"
			(at 0 0 270)
			(layer "F.SilkS")
			(hide yes)
			(effects
				(font
					(size 1.27 1.27)
				)
			)
		)
		(property "Value" ""
			(at 0 0 270)
			(layer "F.Fab")
			(effects
				(font
					(size 1.27 1.27)
				)
			)
		)
		(duplicate_pad_numbers_are_jumpers no)
		(fp_line
			(start -0.7874 0.4064)
			(end -0.7874 -0.4064)
			(stroke
				(width 0.1524)
				(type default)
			)
			(layer "F.SilkS")
		)
		(fp_line
			(start 0.7874 0.4064)
			(end -0.7874 0.4064)
			(stroke
				(width 0.1524)
				(type default)
			)
			(layer "F.SilkS")
		)
		(fp_line
			(start -0.7874 -0.4064)
			(end 0.7874 -0.4064)
			(stroke
				(width 0.1524)
				(type default)
			)
			(layer "F.SilkS")
		)
		(fp_line
			(start 0.7874 -0.4064)
			(end 0.7874 0.4064)
			(stroke
				(width 0.1524)
				(type default)
			)
			(layer "F.SilkS")
		)
		(fp_line
			(start -0.67945 0.3048)
			(end -0.67945 -0.305054)
			(stroke
				(width 0.1)
				(type default)
			)
			(layer "F.Fab")
		)
		(fp_line
			(start -0.12065 0.3048)
			(end -0.67945 0.3048)
			(stroke
				(width 0.1)
				(type default)
			)
			(layer "F.Fab")
		)
		(fp_line
			(start 0.120396 0.3048)
			(end 0.120396 0.2794)
			(stroke
				(width 0.1)
				(type default)
			)
			(layer "F.Fab")
		)
		(fp_line
			(start 0.67945 0.3048)
			(end 0.120396 0.3048)
			(stroke
				(width 0.1)
				(type default)
			)
			(layer "F.Fab")
		)
		(fp_line
			(start -0.12065 0.2794)
			(end -0.12065 0.3048)
			(stroke
				(width 0.1)
				(type default)
			)
			(layer "F.Fab")
		)
		(fp_line
			(start 0.120396 0.2794)
			(end -0.12065 0.2794)
			(stroke
				(width 0.1)
				(type default)
			)
			(layer "F.Fab")
		)
		(fp_line
			(start -0.12065 -0.2794)
			(end 0.12065 -0.2794)
			(stroke
				(width 0.1)
				(type default)
			)
			(layer "F.Fab")
		)
		(fp_line
			(start 0.12065 -0.2794)
			(end 0.12065 -0.3048)
			(stroke
				(width 0.1)
				(type default)
			)
			(layer "F.Fab")
		)
		(fp_line
			(start 0.12065 -0.3048)
			(end 0.67945 -0.3048)
			(stroke
				(width 0.1)
				(type default)
			)
			(layer "F.Fab")
		)
		(fp_line
			(start 0.67945 -0.3048)
			(end 0.67945 0.3048)
			(stroke
				(width 0.1)
				(type default)
			)
			(layer "F.Fab")
		)
		(fp_line
			(start -0.67945 -0.305054)
			(end -0.12065 -0.305054)
			(stroke
				(width 0.1)
				(type default)
			)
			(layer "F.Fab")
		)
		(fp_line
			(start -0.12065 -0.305054)
			(end -0.12065 -0.2794)
			(stroke
				(width 0.1)
				(type default)
			)
			(layer "F.Fab")
		)
		(pad "1" smd circle
			(at -0.40005 0 270)
			(size 0 0)
			(layers "F.Cu" "F.Mask" "F.Paste")
			(net "SW_PVCCFA_EHV_FIVRA_CPU0_BOOT2_")
		)
		(pad "2" smd circle
			(at 0.40005 0 270)
			(size 0 0)
			(layers "F.Cu" "F.Mask" "F.Paste")
			(net "SW_PVCCFA_EHV_FIVRA_CPU0_BOOTR2")
		)
	)
	(footprint ""
		(layer "F.Cu")
		(at 425.163488 -109.12983 90)
		(property "Reference" "PC2091"
			(at 0 0 90)
			(layer "F.SilkS")
			(hide yes)
			(effects
				(font
					(size 1.27 1.27)
				)
			)
		)
		(property "Value" ""
			(at 0 0 90)
			(layer "F.Fab")
			(effects
				(font
					(size 1.27 1.27)
				)
			)
		)
		(duplicate_pad_numbers_are_jumpers no)
		(fp_line
			(start 0.7874 -0.4064)
			(end 0.7874 0.4064)
			(stroke
				(width 0.1524)
				(type default)
			)
			(layer "F.SilkS")
		)
		(fp_line
			(start -0.7874 -0.4064)
			(end 0.7874 -0.4064)
			(stroke
				(width 0.1524)
				(type default)
			)
			(layer "F.SilkS")
		)
		(fp_line
			(start 0.7874 0.4064)
			(end -0.7874 0.4064)
			(stroke
				(width 0.1524)
				(type default)
			)
			(layer "F.SilkS")
		)
		(fp_line
			(start -0.7874 0.4064)
			(end -0.7874 -0.4064)
			(stroke
				(width 0.1524)
				(type default)
			)
			(layer "F.SilkS")
		)
		(fp_line
			(start -0.12065 -0.305054)
			(end -0.12065 -0.2794)
			(stroke
				(width 0.1)
				(type default)
			)
			(layer "F.Fab")
		)
		(fp_line
			(start -0.67945 -0.305054)
			(end -0.12065 -0.305054)
			(stroke
				(width 0.1)
				(type default)
			)
			(layer "F.Fab")
		)
		(fp_line
			(start 0.67945 -0.3048)
			(end 0.67945 0.3048)
			(stroke
				(width 0.1)
				(type default)
			)
			(layer "F.Fab")
		)
		(fp_line
			(start 0.12065 -0.3048)
			(end 0.67945 -0.3048)
			(stroke
				(width 0.1)
				(type default)
			)
			(layer "F.Fab")
		)
		(fp_line
			(start 0.12065 -0.2794)
			(end 0.12065 -0.3048)
			(stroke
				(width 0.1)
				(type default)
			)
			(layer "F.Fab")
		)
		(fp_line
			(start -0.12065 -0.2794)
			(end 0.12065 -0.2794)
			(stroke
				(width 0.1)
				(type default)
			)
			(layer "F.Fab")
		)
		(fp_line
			(start 0.120396 0.2794)
			(end -0.12065 0.2794)
			(stroke
				(width 0.1)
				(type default)
			)
			(layer "F.Fab")
		)
		(fp_line
			(start -0.12065 0.2794)
			(end -0.12065 0.3048)
			(stroke
				(width 0.1)
				(type default)
			)
			(layer "F.Fab")
		)
		(fp_line
			(start 0.67945 0.3048)
			(end 0.120396 0.3048)
			(stroke
				(width 0.1)
				(type default)
			)
			(layer "F.Fab")
		)
		(fp_line
			(start 0.120396 0.3048)
			(end 0.120396 0.2794)
			(stroke
				(width 0.1)
				(type default)
			)
			(layer "F.Fab")
		)
		(fp_line
			(start -0.12065 0.3048)
			(end -0.67945 0.3048)
			(stroke
				(width 0.1)
				(type default)
			)
			(layer "F.Fab")
		)
		(fp_line
			(start -0.67945 0.3048)
			(end -0.67945 -0.305054)
			(stroke
				(width 0.1)
				(type default)
			)
			(layer "F.Fab")
		)
		(pad "1" smd circle
			(at -0.40005 0 90)
			(size 0 0)
			(layers "F.Cu" "F.Mask" "F.Paste")
			(net "P3V3_OCP_SFF_R")
		)
		(pad "2" smd circle
			(at 0.40005 0 90)
			(size 0 0)
			(layers "F.Cu" "F.Mask" "F.Paste")
			(net "GND")
		)
	)
	(footprint ""
		(layer "F.Cu")
		(at 150.83028 -31.829756 180)
		(property "Reference" "R3305"
			(at 0 0 180)
			(layer "F.SilkS")
			(hide yes)
			(effects
				(font
					(size 1.27 1.27)
				)
			)
		)
		(property "Value" ""
			(at 0 0 180)
			(layer "F.Fab")
			(effects
				(font
					(size 1.27 1.27)
				)
			)
		)
		(duplicate_pad_numbers_are_jumpers no)
		(fp_line
			(start 0.7874 0.4064)
			(end -0.7874 0.4064)
			(stroke
				(width 0.1524)
				(type default)
			)
			(layer "F.SilkS")
		)
		(fp_line
			(start 0.7874 -0.4064)
			(end 0.7874 0.4064)
			(stroke
				(width 0.1524)
				(type default)
			)
			(layer "F.SilkS")
		)
		(fp_line
			(start -0.7874 0.4064)
			(end -0.7874 -0.4064)
			(stroke
				(width 0.1524)
				(type default)
			)
			(layer "F.SilkS")
		)
		(fp_line
			(start -0.7874 -0.4064)
			(end 0.7874 -0.4064)
			(stroke
				(width 0.1524)
				(type default)
			)
			(layer "F.SilkS")
		)
		(fp_line
			(start 0.67945 0.3048)
			(end 0.120396 0.3048)
			(stroke
				(width 0.1)
				(type default)
			)
			(layer "F.Fab")
		)
		(fp_line
			(start 0.67945 -0.3048)
			(end 0.67945 0.3048)
			(stroke
				(width 0.1)
				(type default)
			)
			(layer "F.Fab")
		)
		(fp_line
			(start 0.12065 -0.2794)
			(end 0.12065 -0.3048)
			(stroke
				(width 0.1)
				(type default)
			)
			(layer "F.Fab")
		)
		(fp_line
			(start 0.12065 -0.3048)
			(end 0.67945 -0.3048)
			(stroke
				(width 0.1)
				(type default)
			)
			(layer "F.Fab")
		)
		(fp_line
			(start 0.120396 0.3048)
			(end 0.120396 0.2794)
			(stroke
				(width 0.1)
				(type default)
			)
			(layer "F.Fab")
		)
		(fp_line
			(start 0.120396 0.2794)
			(end -0.12065 0.2794)
			(stroke
				(width 0.1)
				(type default)
			)
			(layer "F.Fab")
		)
		(fp_line
			(start -0.12065 0.3048)
			(end -0.67945 0.3048)
			(stroke
				(width 0.1)
				(type default)
			)
			(layer "F.Fab")
		)
		(fp_line
			(start -0.12065 0.2794)
			(end -0.12065 0.3048)
			(stroke
				(width 0.1)
				(type default)
			)
			(layer "F.Fab")
		)
		(fp_line
			(start -0.12065 -0.2794)
			(end 0.12065 -0.2794)
			(stroke
				(width 0.1)
				(type default)
			)
			(layer "F.Fab")
		)
		(fp_line
			(start -0.12065 -0.305054)
			(end -0.12065 -0.2794)
			(stroke
				(width 0.1)
				(type default)
			)
			(layer "F.Fab")
		)
		(fp_line
			(start -0.67945 0.3048)
			(end -0.67945 -0.305054)
			(stroke
				(width 0.1)
				(type default)
			)
			(layer "F.Fab")
		)
		(fp_line
			(start -0.67945 -0.305054)
			(end -0.12065 -0.305054)
			(stroke
				(width 0.1)
				(type default)
			)
			(layer "F.Fab")
		)
		(pad "1" smd circle
			(at -0.40005 0 180)
			(size 0 0)
			(layers "F.Cu" "F.Mask" "F.Paste")
			(net "OCP_SFF_RBT_ARB_IN_MUX1")
		)
		(pad "2" smd circle
			(at 0.40005 0 180)
			(size 0 0)
			(layers "F.Cu" "F.Mask" "F.Paste")
			(net "OCP_SFF_RBT_ARB_IN_MUX1_R")
		)
	)
	(footprint ""
		(layer "F.Cu")
		(at 110.901226 -315.66739 90)
		(property "Reference" "PC586"
			(at 0 0 90)
			(layer "F.SilkS")
			(hide yes)
			(effects
				(font
					(size 1.27 1.27)
				)
			)
		)
		(property "Value" ""
			(at 0 0 90)
			(layer "F.Fab")
			(effects
				(font
					(size 1.27 1.27)
				)
			)
		)
		(duplicate_pad_numbers_are_jumpers no)
		(fp_line
			(start 2.750058 0.999998)
			(end -2.750058 0.999998)
			(stroke
				(width 0.1524)
				(type default)
			)
			(layer "F.SilkS")
		)
		(fp_circle
			(center 0 0.999998)
			(end 0 3.750056)
			(stroke
				(width 0.1524)
				(type default)
			)
			(fill no)
			(layer "F.SilkS")
		)
		(fp_poly
			(pts
				(arc
					(start 2.750058 0.999998)
					(mid 0 3.750056)
					(end -2.750058 0.999998)
				)
			)
			(stroke
				(width 0)
				(type default)
			)
			(fill yes)
			(layer "F.SilkS")
		)
		(fp_circle
			(center 0 0.999998)
			(end 0 3.750056)
			(stroke
				(width 0.1)
				(type default)
			)
			(fill no)
			(layer "F.Fab")
		)
		(pad "1" thru_hole rect
			(at 0 0 90)
			(size 1.5748 1.5748)
			(drill 1.0668)
			(layers "*.Cu" "*.Mask")
			(remove_unused_layers no)
			(net "PVCCIN_CPU1")
			(clearance 0)
			(padstack
				(mode front_inner_back)
				(layer "Inner"
					(shape circle)
					(size 1.5748 1.5748)
					(clearance 0)
				)
				(layer "B.Cu"
					(shape rect)
					(size 1.5748 1.5748)
					(clearance 0)
				)
			)
		)
		(pad "2" thru_hole circle
			(at 0 1.999996 90)
			(size 1.5748 1.5748)
			(drill 1.0668)
			(layers "*.Cu" "*.Mask")
			(remove_unused_layers no)
			(net "GND")
			(clearance 0)
		)
	)
	(footprint ""
		(layer "F.Cu")
		(at 111.332772 -137.854182)
		(property "Reference" "R1822"
			(at 0 0 0)
			(layer "F.SilkS")
			(hide yes)
			(effects
				(font
					(size 1.27 1.27)
				)
			)
		)
		(property "Value" ""
			(at 0 0 0)
			(layer "F.Fab")
			(effects
				(font
					(size 1.27 1.27)
				)
			)
		)
		(duplicate_pad_numbers_are_jumpers no)
		(fp_line
			(start -0.7874 -0.4064)
			(end 0.7874 -0.4064)
			(stroke
				(width 0.1524)
				(type default)
			)
			(layer "F.SilkS")
		)
		(fp_line
			(start -0.7874 0.4064)
			(end -0.7874 -0.4064)
			(stroke
				(width 0.1524)
				(type default)
			)
			(layer "F.SilkS")
		)
		(fp_line
			(start 0.7874 -0.4064)
			(end 0.7874 0.4064)
			(stroke
				(width 0.1524)
				(type default)
			)
			(layer "F.SilkS")
		)
		(fp_line
			(start 0.7874 0.4064)
			(end -0.7874 0.4064)
			(stroke
				(width 0.1524)
				(type default)
			)
			(layer "F.SilkS")
		)
		(fp_line
			(start -0.67945 -0.305054)
			(end -0.12065 -0.305054)
			(stroke
				(width 0.1)
				(type default)
			)
			(layer "F.Fab")
		)
		(fp_line
			(start -0.67945 0.3048)
			(end -0.67945 -0.305054)
			(stroke
				(width 0.1)
				(type default)
			)
			(layer "F.Fab")
		)
		(fp_line
			(start -0.12065 -0.305054)
			(end -0.12065 -0.2794)
			(stroke
				(width 0.1)
				(type default)
			)
			(layer "F.Fab")
		)
		(fp_line
			(start -0.12065 -0.2794)
			(end 0.12065 -0.2794)
			(stroke
				(width 0.1)
				(type default)
			)
			(layer "F.Fab")
		)
		(fp_line
			(start -0.12065 0.2794)
			(end -0.12065 0.3048)
			(stroke
				(width 0.1)
				(type default)
			)
			(layer "F.Fab")
		)
		(fp_line
			(start -0.12065 0.3048)
			(end -0.67945 0.3048)
			(stroke
				(width 0.1)
				(type default)
			)
			(layer "F.Fab")
		)
		(fp_line
			(start 0.120396 0.2794)
			(end -0.12065 0.2794)
			(stroke
				(width 0.1)
				(type default)
			)
			(layer "F.Fab")
		)
		(fp_line
			(start 0.120396 0.3048)
			(end 0.120396 0.2794)
			(stroke
				(width 0.1)
				(type default)
			)
			(layer "F.Fab")
		)
		(fp_line
			(start 0.12065 -0.3048)
			(end 0.67945 -0.3048)
			(stroke
				(width 0.1)
				(type default)
			)
			(layer "F.Fab")
		)
		(fp_line
			(start 0.12065 -0.2794)
			(end 0.12065 -0.3048)
			(stroke
				(width 0.1)
				(type default)
			)
			(layer "F.Fab")
		)
		(fp_line
			(start 0.67945 -0.3048)
			(end 0.67945 0.3048)
			(stroke
				(width 0.1)
				(type default)
			)
			(layer "F.Fab")
		)
		(fp_line
			(start 0.67945 0.3048)
			(end 0.120396 0.3048)
			(stroke
				(width 0.1)
				(type default)
			)
			(layer "F.Fab")
		)
		(pad "1" smd circle
			(at -0.40005 0)
			(size 0 0)
			(layers "F.Cu" "F.Mask" "F.Paste")
			(net "P3V3_AUX")
		)
		(pad "2" smd circle
			(at 0.40005 0)
			(size 0 0)
			(layers "F.Cu" "F.Mask" "F.Paste")
			(net "RST_SMB_SWITCH_N")
		)
	)
	(footprint ""
		(layer "F.Cu")
		(at 129.159 -56.733948 180)
		(property "Reference" "R4626"
			(at 0 0 180)
			(layer "F.SilkS")
			(hide yes)
			(effects
				(font
					(size 1.27 1.27)
				)
			)
		)
		(property "Value" ""
			(at 0 0 180)
			(layer "F.Fab")
			(effects
				(font
					(size 1.27 1.27)
				)
			)
		)
		(duplicate_pad_numbers_are_jumpers no)
		(fp_line
			(start 0.7874 0.4064)
			(end -0.7874 0.4064)
			(stroke
				(width 0.1524)
				(type default)
			)
			(layer "F.SilkS")
		)
		(fp_line
			(start 0.7874 -0.4064)
			(end 0.7874 0.4064)
			(stroke
				(width 0.1524)
				(type default)
			)
			(layer "F.SilkS")
		)
		(fp_line
			(start -0.7874 0.4064)
			(end -0.7874 -0.4064)
			(stroke
				(width 0.1524)
				(type default)
			)
			(layer "F.SilkS")
		)
		(fp_line
			(start -0.7874 -0.4064)
			(end 0.7874 -0.4064)
			(stroke
				(width 0.1524)
				(type default)
			)
			(layer "F.SilkS")
		)
		(fp_line
			(start 0.67945 0.3048)
			(end 0.120396 0.3048)
			(stroke
				(width 0.1)
				(type default)
			)
			(layer "F.Fab")
		)
		(fp_line
			(start 0.67945 -0.3048)
			(end 0.67945 0.3048)
			(stroke
				(width 0.1)
				(type default)
			)
			(layer "F.Fab")
		)
		(fp_line
			(start 0.12065 -0.2794)
			(end 0.12065 -0.3048)
			(stroke
				(width 0.1)
				(type default)
			)
			(layer "F.Fab")
		)
		(fp_line
			(start 0.12065 -0.3048)
			(end 0.67945 -0.3048)
			(stroke
				(width 0.1)
				(type default)
			)
			(layer "F.Fab")
		)
		(fp_line
			(start 0.120396 0.3048)
			(end 0.120396 0.2794)
			(stroke
				(width 0.1)
				(type default)
			)
			(layer "F.Fab")
		)
		(fp_line
			(start 0.120396 0.2794)
			(end -0.12065 0.2794)
			(stroke
				(width 0.1)
				(type default)
			)
			(layer "F.Fab")
		)
		(fp_line
			(start -0.12065 0.3048)
			(end -0.67945 0.3048)
			(stroke
				(width 0.1)
				(type default)
			)
			(layer "F.Fab")
		)
		(fp_line
			(start -0.12065 0.2794)
			(end -0.12065 0.3048)
			(stroke
				(width 0.1)
				(type default)
			)
			(layer "F.Fab")
		)
		(fp_line
			(start -0.12065 -0.2794)
			(end 0.12065 -0.2794)
			(stroke
				(width 0.1)
				(type default)
			)
			(layer "F.Fab")
		)
		(fp_line
			(start -0.12065 -0.305054)
			(end -0.12065 -0.2794)
			(stroke
				(width 0.1)
				(type default)
			)
			(layer "F.Fab")
		)
		(fp_line
			(start -0.67945 0.3048)
			(end -0.67945 -0.305054)
			(stroke
				(width 0.1)
				(type default)
			)
			(layer "F.Fab")
		)
		(fp_line
			(start -0.67945 -0.305054)
			(end -0.12065 -0.305054)
			(stroke
				(width 0.1)
				(type default)
			)
			(layer "F.Fab")
		)
		(pad "1" smd circle
			(at -0.40005 0 180)
			(size 0 0)
			(layers "F.Cu" "F.Mask" "F.Paste")
			(net "JTAG_BMC_TDO")
		)
		(pad "2" smd circle
			(at 0.40005 0 180)
			(size 0 0)
			(layers "F.Cu" "F.Mask" "F.Paste")
			(net "JTAG_BMC_TDO_R")
		)
	)
	(footprint ""
		(layer "F.Cu")
		(at 9.739884 -360.76382)
		(property "Reference" "H125"
			(at -2.056384 -8.033258 0)
			(unlocked yes)
			(layer "F.SilkS")
			(effects
				(font
					(size 0.7874 0.5842)
					(thickness 0.1524)
				)
				(justify left)
			)
		)
		(property "Value" ""
			(at 0 0 0)
			(layer "F.Fab")
			(effects
				(font
					(size 1.27 1.27)
				)
			)
		)
		(duplicate_pad_numbers_are_jumpers no)
		(fp_circle
			(center 0 0)
			(end 5.8166 0)
			(stroke
				(width 0.1524)
				(type default)
			)
			(fill no)
			(layer "F.SilkS")
		)
		(fp_circle
			(center 0 0)
			(end 5.8166 0)
			(stroke
				(width 0.1524)
				(type default)
			)
			(fill no)
			(layer "B.SilkS")
		)
		(fp_circle
			(center 0 0)
			(end 5.8166 0)
			(stroke
				(width 0.1)
				(type default)
			)
			(fill no)
			(layer "B.Fab")
		)
		(fp_circle
			(center 0 0)
			(end 5.8166 0)
			(stroke
				(width 0.1)
				(type default)
			)
			(fill no)
			(layer "F.Fab")
		)
		(pad "" np_thru_hole circle
			(at 0 0)
			(size 10.0076 10.0076)
			(drill 10.0076)
			(layers "*.Cu" "*.Mask")
			(clearance 0.381)
			(thermal_gap 0.381)
		)
		(zone
			(layers "F.Cu" "B.Cu" "In1.Cu" "In2.Cu" "In3.Cu" "In4.Cu" "In5.Cu" "In6.Cu"
				"In7.Cu" "In8.Cu" "In9.Cu" "In10.Cu" "In11.Cu" "In12.Cu" "In13.Cu" "In14.Cu"
				"In15.Cu" "In16.Cu"
			)
			(hatch none 0.5)
			(connect_pads
				(clearance 0)
			)
			(min_thickness 0.25)
			(keepout
				(tracks not_allowed)
				(vias allowed)
				(pads allowed)
				(copperpour not_allowed)
				(footprints allowed)
			)
			(placement
				(enabled no)
				(sheetname "")
			)
			(fill
				(thermal_gap 0.5)
				(thermal_bridge_width 0.5)
				(island_removal_mode 0)
			)
			(polygon
				(pts
					(arc
						(start 15.251684 -360.76382)
						(mid 4.228084 -360.76382)
						(end 15.251684 -360.76382)
					)
				)
			)
		)
	)
)
